(kicad_pcb
	(version 20260206)
	(generator "pcbnew")
	(generator_version "10.0")
	(general
		(thickness 1.6)
		(legacy_teardrops no)
	)
	(paper "A4")
	(title_block
		(title "Wiwynn_Tioga_Pass_MB.brd")
		(comment 1 "Tioga Pass / footprints 4282-4289 of 4770")
	)
	(layers
		(0 "F.Cu" signal "TOP")
		(4 "In1.Cu" signal "L2GND")
		(6 "In2.Cu" signal "L3")
		(8 "In3.Cu" signal "L4GND")
		(10 "In4.Cu" signal "L5")
		(12 "In5.Cu" signal "L6GND")
		(14 "In6.Cu" signal "L7VCC")
		(16 "In7.Cu" signal "L8VCC")
		(18 "In8.Cu" signal "L9GND")
		(20 "In9.Cu" signal "L10")
		(22 "In10.Cu" signal "L11GND")
		(24 "In11.Cu" signal "L12")
		(26 "In12.Cu" signal "L13GND")
		(2 "B.Cu" signal "BOTTOM")
		(9 "F.Adhes" user "F.Adhesive")
		(11 "B.Adhes" user "B.Adhesive")
		(13 "F.Paste" user "Package Geometry/Pastemask Top")
		(15 "B.Paste" user "Package Geometry/Pastemask Bottom")
		(5 "F.SilkS" user "Ref Des/Silkscreen Top")
		(7 "B.SilkS" user "Ref Des/Silkscreen Bottom")
		(1 "F.Mask" user "Board Geometry/Soldermask Top")
		(3 "B.Mask" user "Board Geometry/Soldermask Bottom")
		(17 "Dwgs.User" user "User.Drawings")
		(19 "Cmts.User" user "User.Comments")
		(21 "Eco1.User" user "User.Eco1")
		(23 "Eco2.User" user "User.Eco2")
		(25 "Edge.Cuts" user "Board Geometry/Outline")
		(27 "Margin" user)
		(31 "F.CrtYd" user "Package Geometry/Place Bound Top")
		(29 "B.CrtYd" user "Package Geometry/Place Bound Bottom")
		(35 "F.Fab" user "Ref Des/Assembly Top")
		(33 "B.Fab" user "Ref Des/Assembly Bottom")
	)
	(footprint ""
		(layer "B.Cu")
		(at 168.927526 -146.713448 90)
		(property "Reference" "C6L5"
			(at 0 0 90)
			(layer "B.SilkS")
			(hide yes)
			(effects
				(font
					(size 1.27 1.27)
				)
				(justify mirror)
			)
		)
		(property "Value" ""
			(at 0 0 90)
			(layer "B.Fab")
			(effects
				(font
					(size 1.27 1.27)
				)
				(justify mirror)
			)
		)
		(duplicate_pad_numbers_are_jumpers no)
		(fp_rect
			(start 0.4953 1.6002)
			(end -0.4953 -0.2032)
			(stroke
				(width 0)
				(type default)
			)
			(fill no)
			(layer "B.CrtYd")
		)
		(fp_line
			(start 0.4953 -0.2032)
			(end -0.4953 -0.2032)
			(stroke
				(width 0.1)
				(type default)
			)
			(layer "B.Fab")
		)
		(fp_line
			(start -0.4953 -0.2032)
			(end -0.4953 1.6002)
			(stroke
				(width 0.1)
				(type default)
			)
			(layer "B.Fab")
		)
		(fp_line
			(start 0.4953 1.6002)
			(end 0.4953 -0.2032)
			(stroke
				(width 0.1)
				(type default)
			)
			(layer "B.Fab")
		)
		(fp_line
			(start -0.4953 1.6002)
			(end 0.4953 1.6002)
			(stroke
				(width 0.1)
				(type default)
			)
			(layer "B.Fab")
		)
		(pad "1" smd rect
			(at 0 0 270)
			(size 0.762 0.889)
			(layers "B.Cu" "B.Mask" "B.Paste")
			(net "PVDDQ_KLM")
		)
		(pad "2" smd rect
			(at 0 1.397 270)
			(size 0.762 0.889)
			(layers "B.Cu" "B.Mask" "B.Paste")
			(net "GND")
		)
		(zone
			(layer "B.Cu")
			(hatch none 0.5)
			(connect_pads
				(clearance 0)
			)
			(min_thickness 0.25)
			(keepout
				(tracks not_allowed)
				(vias allowed)
				(pads allowed)
				(copperpour not_allowed)
				(footprints allowed)
			)
			(placement
				(enabled no)
				(sheetname "")
			)
			(fill
				(thermal_gap 0.5)
				(thermal_bridge_width 0.5)
				(island_removal_mode 0)
			)
			(polygon
				(pts
					(xy 169.880026 -147.094448) (xy 169.372026 -147.094448) (xy 169.372026 -146.332448) (xy 169.880026 -146.332448)
				)
			)
		)
	)
	(footprint ""
		(layer "B.Cu")
		(at 269.559532 -149.8092 90)
		(property "Reference" "C5G70"
			(at -1.14681 0.76708 180)
			(unlocked yes)
			(layer "B.SilkS")
			(effects
				(font
					(size 0.7874 0.5842)
					(thickness 0.1524)
				)
				(justify mirror)
			)
		)
		(property "Value" ""
			(at 0 0 90)
			(layer "B.Fab")
			(effects
				(font
					(size 1.27 1.27)
				)
				(justify mirror)
			)
		)
		(duplicate_pad_numbers_are_jumpers no)
		(fp_rect
			(start -0.4953 -0.2032)
			(end 0.4953 1.6002)
			(stroke
				(width 0)
				(type default)
			)
			(fill no)
			(layer "B.CrtYd")
		)
		(fp_line
			(start 0.4953 -0.2032)
			(end -0.4953 -0.2032)
			(stroke
				(width 0.1)
				(type default)
			)
			(layer "B.Fab")
		)
		(fp_line
			(start -0.4953 -0.2032)
			(end -0.4953 1.6002)
			(stroke
				(width 0.1)
				(type default)
			)
			(layer "B.Fab")
		)
		(fp_line
			(start 0.4953 1.6002)
			(end 0.4953 -0.2032)
			(stroke
				(width 0.1)
				(type default)
			)
			(layer "B.Fab")
		)
		(fp_line
			(start -0.4953 1.6002)
			(end 0.4953 1.6002)
			(stroke
				(width 0.1)
				(type default)
			)
			(layer "B.Fab")
		)
		(pad "1" smd rect
			(at 0 0 270)
			(size 0.762 0.889)
			(layers "B.Cu" "B.Mask" "B.Paste")
			(net "PVDDQ_DEF")
		)
		(pad "2" smd rect
			(at 0 1.397 270)
			(size 0.762 0.889)
			(layers "B.Cu" "B.Mask" "B.Paste")
			(net "GND")
		)
		(zone
			(layer "B.Cu")
			(hatch none 0.5)
			(connect_pads
				(clearance 0)
			)
			(min_thickness 0.25)
			(keepout
				(tracks not_allowed)
				(vias allowed)
				(pads allowed)
				(copperpour not_allowed)
				(footprints allowed)
			)
			(placement
				(enabled no)
				(sheetname "")
			)
			(fill
				(thermal_gap 0.5)
				(thermal_bridge_width 0.5)
				(island_removal_mode 0)
			)
			(polygon
				(pts
					(xy 270.004032 -149.4282) (xy 270.512032 -149.4282) (xy 270.512032 -150.1902) (xy 270.004032 -150.1902)
				)
			)
		)
	)
	(footprint ""
		(layer "B.Cu")
		(at 269.502128 -156.960824 90)
		(property "Reference" "C5L3"
			(at 0 0 90)
			(layer "B.SilkS")
			(hide yes)
			(effects
				(font
					(size 1.27 1.27)
				)
				(justify mirror)
			)
		)
		(property "Value" ""
			(at 0 0 90)
			(layer "B.Fab")
			(effects
				(font
					(size 1.27 1.27)
				)
				(justify mirror)
			)
		)
		(duplicate_pad_numbers_are_jumpers no)
		(fp_rect
			(start 0.7239 1.9939)
			(end -0.7239 -0.2159)
			(stroke
				(width 0)
				(type default)
			)
			(fill no)
			(layer "B.CrtYd")
		)
		(fp_line
			(start 0.7239 -0.2159)
			(end 0.7239 1.9939)
			(stroke
				(width 0.1)
				(type default)
			)
			(layer "B.Fab")
		)
		(fp_line
			(start -0.7239 -0.2159)
			(end 0.7239 -0.2159)
			(stroke
				(width 0.1)
				(type default)
			)
			(layer "B.Fab")
		)
		(fp_line
			(start 0.7239 1.9939)
			(end -0.7239 1.9939)
			(stroke
				(width 0.1)
				(type default)
			)
			(layer "B.Fab")
		)
		(fp_line
			(start -0.7239 1.9939)
			(end -0.7239 -0.2159)
			(stroke
				(width 0.1)
				(type default)
			)
			(layer "B.Fab")
		)
		(pad "1" smd rect
			(at 0 0 270)
			(size 1.27 1.016)
			(layers "B.Cu" "B.Mask" "B.Paste")
			(net "PVDDQ_DEF")
		)
		(pad "2" smd rect
			(at 0 1.778 270)
			(size 1.27 1.016)
			(layers "B.Cu" "B.Mask" "B.Paste")
			(net "GND")
		)
		(zone
			(layer "B.Cu")
			(hatch none 0.5)
			(connect_pads
				(clearance 0)
			)
			(min_thickness 0.25)
			(keepout
				(tracks not_allowed)
				(vias allowed)
				(pads allowed)
				(copperpour not_allowed)
				(footprints allowed)
			)
			(placement
				(enabled no)
				(sheetname "")
			)
			(fill
				(thermal_gap 0.5)
				(thermal_bridge_width 0.5)
				(island_removal_mode 0)
			)
			(polygon
				(pts
					(xy 270.772128 -157.595824) (xy 270.010128 -157.595824) (xy 270.010128 -156.325824) (xy 270.772128 -156.325824)
				)
			)
		)
	)
	(footprint ""
		(layer "B.Cu")
		(at 465.0232 -130.5052 90)
		(property "Reference" "U1M3"
			(at -5.83819 0.86614 0)
			(unlocked yes)
			(layer "B.SilkS")
			(effects
				(font
					(size 0.7874 0.5842)
					(thickness 0.1524)
				)
				(justify mirror)
			)
		)
		(property "Value" ""
			(at 0 0 90)
			(layer "B.Fab")
			(effects
				(font
					(size 1.27 1.27)
				)
				(justify mirror)
			)
		)
		(duplicate_pad_numbers_are_jumpers no)
		(fp_circle
			(center 1.395222 -0.155448)
			(end 1.395222 -0.028448)
			(stroke
				(width 0.254)
				(type default)
			)
			(fill no)
			(layer "B.SilkS")
		)
		(fp_rect
			(start -0.45847 2.400046)
			(end -2.20853 -0.500126)
			(stroke
				(width 0)
				(type default)
			)
			(fill no)
			(layer "B.CrtYd")
		)
		(fp_line
			(start -0.45847 -0.500126)
			(end -2.20853 -0.500126)
			(stroke
				(width 0.1)
				(type default)
			)
			(layer "B.Fab")
		)
		(fp_line
			(start -2.20853 -0.500126)
			(end -2.20853 2.400046)
			(stroke
				(width 0.1)
				(type default)
			)
			(layer "B.Fab")
		)
		(fp_line
			(start -0.45847 2.400046)
			(end -0.45847 -0.500126)
			(stroke
				(width 0.1)
				(type default)
			)
			(layer "B.Fab")
		)
		(fp_line
			(start -2.20853 2.400046)
			(end -0.45847 2.400046)
			(stroke
				(width 0.1)
				(type default)
			)
			(layer "B.Fab")
		)
		(fp_circle
			(center 1.395222 -0.155448)
			(end 1.395222 -0.028448)
			(stroke
				(width 0.254)
				(type default)
			)
			(fill no)
			(layer "B.Fab")
		)
		(pad "1" smd rect
			(at 0 0 270)
			(size 1.397 0.508)
			(layers "B.Cu" "B.Mask" "B.Paste")
			(net "P5V_USB")
		)
		(pad "2" smd rect
			(at 0 0.94996 270)
			(size 1.397 0.508)
			(layers "B.Cu" "B.Mask" "B.Paste")
			(net "GND")
		)
		(pad "3" smd rect
			(at 0 1.89992 270)
			(size 1.397 0.508)
			(layers "B.Cu" "B.Mask" "B.Paste")
			(net "FM_OC0_USB_N")
		)
		(pad "4" smd rect
			(at -2.667 1.89992 270)
			(size 1.397 0.508)
			(layers "B.Cu" "B.Mask" "B.Paste")
			(net "FM_USB_P0_EN_R_N")
		)
		(pad "5" smd rect
			(at -2.667 0 270)
			(size 1.397 0.508)
			(layers "B.Cu" "B.Mask" "B.Paste")
			(net "P5V_TPS2061")
		)
	)
	(footprint ""
		(layer "B.Cu")
		(at 480.108006 -34.980118 -90)
		(property "Reference" "R2T52"
			(at 0 0 90)
			(layer "B.SilkS")
			(hide yes)
			(effects
				(font
					(size 1.27 1.27)
				)
				(justify mirror)
			)
		)
		(property "Value" ""
			(at 0 0 90)
			(layer "B.Fab")
			(effects
				(font
					(size 1.27 1.27)
				)
				(justify mirror)
			)
		)
		(duplicate_pad_numbers_are_jumpers no)
		(fp_poly
			(pts
				(xy 0.4953 -0.2032) (xy -0.4953 -0.2032) (xy -0.4953 1.6002) (xy 0.4953 1.6002)
			)
			(stroke
				(width 0)
				(type default)
			)
			(fill no)
			(layer "B.CrtYd")
		)
		(fp_line
			(start -0.4953 1.6002)
			(end 0.4953 1.6002)
			(stroke
				(width 0.1)
				(type default)
			)
			(layer "B.Fab")
		)
		(fp_line
			(start 0.4953 1.6002)
			(end 0.4953 -0.2032)
			(stroke
				(width 0.1)
				(type default)
			)
			(layer "B.Fab")
		)
		(fp_line
			(start -0.4953 -0.2032)
			(end -0.4953 1.6002)
			(stroke
				(width 0.1)
				(type default)
			)
			(layer "B.Fab")
		)
		(fp_line
			(start 0.4953 -0.2032)
			(end -0.4953 -0.2032)
			(stroke
				(width 0.1)
				(type default)
			)
			(layer "B.Fab")
		)
		(pad "1" smd rect
			(at 0 0 90)
			(size 0.762 0.889)
			(layers "B.Cu" "B.Mask" "B.Paste")
			(net "P3V3_STBY_MNG")
		)
		(pad "2" smd rect
			(at 0 1.397 90)
			(size 0.762 0.889)
			(layers "B.Cu" "B.Mask" "B.Paste")
			(net "P3V3_STBY_MNG_RMII")
		)
		(zone
			(layer "B.Cu")
			(hatch none 0.5)
			(connect_pads
				(clearance 0)
			)
			(min_thickness 0.25)
			(keepout
				(tracks allowed)
				(vias not_allowed)
				(pads allowed)
				(copperpour not_allowed)
				(footprints allowed)
			)
			(placement
				(enabled no)
				(sheetname "")
			)
			(fill
				(thermal_gap 0.5)
				(thermal_bridge_width 0.5)
				(island_removal_mode 0)
			)
			(polygon
				(pts
					(xy 479.155506 -35.361118) (xy 479.663506 -35.361118) (xy 479.663506 -34.599118) (xy 479.155506 -34.599118)
				)
			)
		)
		(zone
			(layer "B.Cu")
			(hatch none 0.5)
			(connect_pads
				(clearance 0)
			)
			(min_thickness 0.25)
			(keepout
				(tracks not_allowed)
				(vias allowed)
				(pads allowed)
				(copperpour not_allowed)
				(footprints allowed)
			)
			(placement
				(enabled no)
				(sheetname "")
			)
			(fill
				(thermal_gap 0.5)
				(thermal_bridge_width 0.5)
				(island_removal_mode 0)
			)
			(polygon
				(pts
					(xy 479.155506 -34.599118) (xy 479.663506 -34.599118) (xy 479.663506 -35.361118) (xy 479.155506 -35.361118)
				)
			)
		)
	)
	(footprint ""
		(layer "B.Cu")
		(at 374.408446 -88.236806 180)
		(property "Reference" "R3N14"
			(at 0.8382 -0.67818 180)
			(unlocked yes)
			(layer "B.SilkS")
			(effects
				(font
					(size 0.4064 0.254)
					(thickness 0.1524)
				)
				(justify left mirror)
			)
		)
		(property "Value" ""
			(at 0 0 0)
			(layer "B.Fab")
			(effects
				(font
					(size 1.27 1.27)
				)
				(justify mirror)
			)
		)
		(duplicate_pad_numbers_are_jumpers no)
		(fp_poly
			(pts
				(xy 0.2794 -0.1016) (xy -0.2794 -0.1016) (xy -0.2794 0.9906) (xy 0.2794 0.9906)
			)
			(stroke
				(width 0)
				(type default)
			)
			(fill no)
			(layer "B.CrtYd")
		)
		(fp_line
			(start 0.2794 0.9906)
			(end -0.2794 0.9906)
			(stroke
				(width 0.1)
				(type default)
			)
			(layer "B.Fab")
		)
		(fp_line
			(start 0.2794 -0.1016)
			(end 0.2794 0.9906)
			(stroke
				(width 0.1)
				(type default)
			)
			(layer "B.Fab")
		)
		(fp_line
			(start -0.2794 0.9906)
			(end -0.2794 -0.1016)
			(stroke
				(width 0.1)
				(type default)
			)
			(layer "B.Fab")
		)
		(fp_line
			(start -0.2794 -0.1016)
			(end 0.2794 -0.1016)
			(stroke
				(width 0.1)
				(type default)
			)
			(layer "B.Fab")
		)
		(pad "1" smd rect
			(at 0 0)
			(size 0.508 0.508)
			(layers "B.Cu" "B.Mask" "B.Paste")
			(net "H_PM_SYNC_GTL")
		)
		(pad "2" smd rect
			(at 0 0.889)
			(size 0.508 0.508)
			(layers "B.Cu" "B.Mask" "B.Paste")
			(net "GND")
		)
		(zone
			(layer "B.Cu")
			(hatch none 0.5)
			(connect_pads
				(clearance 0)
			)
			(min_thickness 0.25)
			(keepout
				(tracks not_allowed)
				(vias allowed)
				(pads allowed)
				(copperpour not_allowed)
				(footprints allowed)
			)
			(placement
				(enabled no)
				(sheetname "")
			)
			(fill
				(thermal_gap 0.5)
				(thermal_bridge_width 0.5)
				(island_removal_mode 0)
			)
			(polygon
				(pts
					(xy 374.154446 -88.871806) (xy 374.662446 -88.871806) (xy 374.662446 -88.490806) (xy 374.154446 -88.490806)
				)
			)
		)
		(zone
			(layer "B.Cu")
			(hatch none 0.5)
			(connect_pads
				(clearance 0)
			)
			(min_thickness 0.25)
			(keepout
				(tracks allowed)
				(vias not_allowed)
				(pads allowed)
				(copperpour not_allowed)
				(footprints allowed)
			)
			(placement
				(enabled no)
				(sheetname "")
			)
			(fill
				(thermal_gap 0.5)
				(thermal_bridge_width 0.5)
				(island_removal_mode 0)
			)
			(polygon
				(pts
					(xy 374.154446 -88.490806) (xy 374.662446 -88.490806) (xy 374.662446 -88.871806) (xy 374.154446 -88.871806)
				)
			)
		)
	)
	(footprint ""
		(layer "B.Cu")
		(at 308.874414 -164.908992 90)
		(property "Reference" "T1D16"
			(at 0 0 90)
			(layer "B.SilkS")
			(hide yes)
			(effects
				(font
					(size 1.27 1.27)
				)
				(justify mirror)
			)
		)
		(property "Value" "*"
			(at 3.4036 -4.46405 90)
			(unlocked yes)
			(layer "B.Fab")
			(hide yes)
			(effects
				(font
					(size 0.889 0.889)
					(thickness 0.1524)
				)
				(justify mirror)
			)
		)
		(property "Device Type" "TEST-PAD-12P-1-GP-U_DISCRET-GBA"
			(at 3.4036 -5.98805 90)
			(unlocked yes)
			(layer "B.Fab")
			(hide yes)
			(effects
				(font
					(size 0.889 0.889)
					(thickness 0.1524)
				)
				(justify mirror)
			)
		)
		(duplicate_pad_numbers_are_jumpers no)
		(fp_line
			(start 2.3876 -4.826)
			(end -2.3622 -4.826)
			(stroke
				(width 0.1524)
				(type default)
			)
			(layer "B.SilkS")
		)
		(fp_line
			(start -2.3622 -4.826)
			(end -2.3622 3.4798)
			(stroke
				(width 0.1524)
				(type default)
			)
			(layer "B.SilkS")
		)
		(fp_line
			(start 2.3876 3.4798)
			(end 2.3876 -4.826)
			(stroke
				(width 0.1524)
				(type default)
			)
			(layer "B.SilkS")
		)
		(fp_line
			(start -2.3622 3.4798)
			(end 2.3876 3.4798)
			(stroke
				(width 0.1524)
				(type default)
			)
			(layer "B.SilkS")
		)
		(fp_rect
			(start 2.6416 3.7338)
			(end -2.6162 -5.08)
			(stroke
				(width 0)
				(type default)
			)
			(fill no)
			(layer "B.CrtYd")
		)
		(fp_rect
			(start 2.6416 3.7338)
			(end -2.6162 -5.08)
			(stroke
				(width 0)
				(type default)
			)
			(fill no)
			(layer "B.Fab")
		)
		(pad "1" smd circle
			(at -0.496824 -1.301496 270)
			(size 0.6604 0.6604)
			(layers "B.Cu" "B.Mask" "B.Paste")
			(net "L3_85OHM_10INCH_DN")
		)
		(pad "2" smd circle
			(at 0.503936 -1.301496 270)
			(size 0.6604 0.6604)
			(layers "B.Cu" "B.Mask" "B.Paste")
			(net "L3_85OHM_10INCH_DP")
		)
		(pad "3" smd custom
			(at 0.00889 0.370078 270)
			(size 0.74295 0.74295)
			(layers "B.Cu" "B.Mask" "B.Paste")
			(net "GND")
			(options
				(clearance outline)
				(anchor circle)
			)
			(primitives
				(gr_poly
					(pts
						(xy -2.1209 -1.4859) (xy 2.1209 -1.4859) (xy 2.1209 1.4859) (xy 1.08585 1.4859) (xy 1.08585 0.4699)
						(xy -1.08585 0.4699) (xy -1.08585 1.4859) (xy -2.1209 1.4859)
					)
					(width 0)
					(fill yes)
				)
			)
		)
		(pad "4" thru_hole circle
			(at -1.266444 -3.851656 270)
			(size 1.4478 1.4478)
			(drill 1.0414)
			(layers "*.Cu" "*.Mask")
			(remove_unused_layers no)
			(net "GND")
			(clearance 0.1524)
			(thermal_gap 0.1524)
		)
		(pad "5" thru_hole circle
			(at 1.273556 -3.851656 270)
			(size 1.4478 1.4478)
			(drill 1.0414)
			(layers "*.Cu" "*.Mask")
			(remove_unused_layers no)
			(net "GND")
			(clearance 0.1524)
			(thermal_gap 0.1524)
		)
		(pad "6" thru_hole circle
			(at -1.266444 2.498344 270)
			(size 1.4478 1.4478)
			(drill 1.0414)
			(layers "*.Cu" "*.Mask")
			(remove_unused_layers no)
			(net "GND")
			(clearance 0.1524)
			(thermal_gap 0.1524)
		)
		(pad "7" thru_hole circle
			(at 1.273556 2.498344 270)
			(size 1.4478 1.4478)
			(drill 1.0414)
			(layers "*.Cu" "*.Mask")
			(remove_unused_layers no)
			(net "GND")
			(clearance 0.1524)
			(thermal_gap 0.1524)
		)
		(pad "8" thru_hole circle
			(at -1.27 -0.4572 270)
			(size 0.7112 0.7112)
			(drill 0.4064)
			(layers "*.Cu" "*.Mask")
			(remove_unused_layers no)
			(net "GND")
			(clearance 0.1016)
			(thermal_gap 0.1016)
		)
		(pad "9" thru_hole circle
			(at -1.27 0.762 270)
			(size 0.7112 0.7112)
			(drill 0.4064)
			(layers "*.Cu" "*.Mask")
			(remove_unused_layers no)
			(net "GND")
			(clearance 0.1016)
			(thermal_gap 0.1016)
		)
		(pad "10" thru_hole circle
			(at 0.0254 0.762 270)
			(size 0.7112 0.7112)
			(drill 0.4064)
			(layers "*.Cu" "*.Mask")
			(remove_unused_layers no)
			(net "GND")
			(clearance 0.1016)
			(thermal_gap 0.1016)
		)
		(pad "11" thru_hole circle
			(at 1.27 0.762 270)
			(size 0.7112 0.7112)
			(drill 0.4064)
			(layers "*.Cu" "*.Mask")
			(remove_unused_layers no)
			(net "GND")
			(clearance 0.1016)
			(thermal_gap 0.1016)
		)
		(pad "12" thru_hole circle
			(at 1.27 -0.4572 270)
			(size 0.7112 0.7112)
			(drill 0.4064)
			(layers "*.Cu" "*.Mask")
			(remove_unused_layers no)
			(net "GND")
			(clearance 0.1016)
			(thermal_gap 0.1016)
		)
	)
	(footprint ""
		(layer "B.Cu")
		(at 181.5846 -61.03366 180)
		(property "Reference" "C22W18"
			(at 0 0 0)
			(layer "B.SilkS")
			(hide yes)
			(effects
				(font
					(size 1.27 1.27)
				)
				(justify mirror)
			)
		)
		(property "Value" "*"
			(at 0.0762 -6.2357 180)
			(unlocked yes)
			(layer "B.Fab")
			(hide yes)
			(effects
				(font
					(size 1.27 1.016)
					(thickness 0.1524)
				)
				(justify mirror)
			)
		)
		(property "Device Type" "SC22U16V5MX-4-GP_SMD-BCG5-SC22A"
			(at 0.0762 -8.2677 180)
			(unlocked yes)
			(layer "B.Fab")
			(hide yes)
			(effects
				(font
					(size 1.27 1.016)
					(thickness 0.1524)
				)
				(justify mirror)
			)
		)
		(duplicate_pad_numbers_are_jumpers no)
		(fp_line
			(start -0.635 0)
			(end 0.635 0)
			(stroke
				(width 0.508)
				(type default)
			)
			(layer "B.SilkS")
		)
		(fp_rect
			(start 0.9652 1.778)
			(end -0.9652 -1.778)
			(stroke
				(width 0)
				(type default)
			)
			(fill no)
			(layer "B.CrtYd")
		)
		(fp_poly
			(pts
				(xy 0.9652 -1.778) (xy -0.9652 -1.778) (xy -0.9652 1.778) (xy 0.9652 1.778)
			)
			(stroke
				(width 0)
				(type default)
			)
			(fill no)
			(layer "B.Fab")
		)
		(pad "1" smd rect
			(at 0 -0.9652)
			(size 1.397 1.143)
			(layers "B.Cu" "B.Mask" "B.Paste")
			(net "VR_FET_SW_P12V_STBY_PVCCIN_CPU0")
		)
		(pad "2" smd rect
			(at 0 0.9652)
			(size 1.397 1.143)
			(layers "B.Cu" "B.Mask" "B.Paste")
			(net "GND")
		)
	)
)
